(kicad_pcb
	(version 20260206)
	(generator "pcbnew")
	(generator_version "10.0")
	(general
		(thickness 1.6)
		(legacy_teardrops no)
	)
	(paper "A4")
	(title_block
		(title "netronome-mezz — pcbd0082-001_rev01_jul9_a.brd")
		(comment 1 "Open CloudServer (Microsoft) / footprints 639-647 of 714")
	)
	(layers
		(0 "F.Cu" signal "TOP")
		(4 "In1.Cu" signal "02_GND")
		(6 "In2.Cu" signal "03_SIG")
		(8 "In3.Cu" signal "04_SIG")
		(10 "In4.Cu" signal "05_GND")
		(12 "In5.Cu" signal "06_PWR1")
		(14 "In6.Cu" signal "07_SIG")
		(16 "In7.Cu" signal "08_SIG")
		(18 "In8.Cu" signal "09_GND")
		(2 "B.Cu" signal "BOTTOM")
		(9 "F.Adhes" user "F.Adhesive")
		(11 "B.Adhes" user "B.Adhesive")
		(13 "F.Paste" user "Package Geometry/Pastemask Top")
		(15 "B.Paste" user "Package Geometry/Pastemask Bottom")
		(5 "F.SilkS" user "Ref Des/Silkscreen Top")
		(7 "B.SilkS" user "Ref Des/Silkscreen Bottom")
		(1 "F.Mask" user "Board Geometry/Soldermask Top")
		(3 "B.Mask" user "Board Geometry/Soldermask Bottom")
		(17 "Dwgs.User" user "User.Drawings")
		(19 "Cmts.User" user "User.Comments")
		(21 "Eco1.User" user "User.Eco1")
		(23 "Eco2.User" user "User.Eco2")
		(25 "Edge.Cuts" user "Board Geometry/Outline")
		(27 "Margin" user)
		(31 "F.CrtYd" user "Package Geometry/Place Bound Top")
		(29 "B.CrtYd" user "Package Geometry/Place Bound Bottom")
		(35 "F.Fab" user "Ref Des/Assembly Top")
		(33 "B.Fab" user "Ref Des/Assembly Bottom")
		(45 "User.4" user "COMPVAL_TYPE_BOTTOM")
	)
	(footprint ""
		(layer "B.Cu")
		(at 32.766 32.639)
		(property "Reference" "R82"
			(at -0.02667 3.683 270)
			(unlocked yes)
			(layer "B.SilkS")
			(effects
				(font
					(size 0.7874 0.5842)
					(thickness 0.127)
				)
				(justify left mirror)
			)
		)
		(property "Value" "4.75K"
			(at 0.148158 1.3462 270)
			(unlocked yes)
			(layer "B.Fab")
			(hide yes)
			(effects
				(font
					(size 1.27 0.9652)
					(thickness 0.000001)
				)
				(justify left mirror)
			)
		)
		(property "Device Type" "REST4024"
			(at 0.148158 1.3462 270)
			(unlocked yes)
			(layer "B.Fab")
			(hide yes)
			(effects
				(font
					(size 1.27 0.9652)
					(thickness 0.000001)
				)
				(justify left mirror)
			)
		)
		(duplicate_pad_numbers_are_jumpers no)
		(fp_poly
			(pts
				(xy -0.635 1.0668) (xy -0.635 -1.0668) (xy 0.635 -1.0668) (xy 0.635 1.0668)
			)
			(stroke
				(width 0)
				(type default)
			)
			(fill no)
			(layer "B.CrtYd")
		)
		(fp_line
			(start -0.254 -0.508)
			(end -0.254 0.508)
			(stroke
				(width 0.0254)
				(type default)
			)
			(layer "B.Fab")
		)
		(fp_line
			(start -0.254 0.508)
			(end 0.254 0.508)
			(stroke
				(width 0.0254)
				(type default)
			)
			(layer "B.Fab")
		)
		(fp_line
			(start 0.254 -0.508)
			(end -0.254 -0.508)
			(stroke
				(width 0.0254)
				(type default)
			)
			(layer "B.Fab")
		)
		(fp_line
			(start 0.254 0.508)
			(end 0.254 -0.508)
			(stroke
				(width 0.0254)
				(type default)
			)
			(layer "B.Fab")
		)
		(pad "1" smd rect
			(at 0 -0.4191 180)
			(size 0.508 0.5334)
			(layers "B.Cu" "B.Mask" "B.Paste")
			(net "GND")
		)
		(pad "2" smd rect
			(at 0 0.4191 180)
			(size 0.508 0.5334)
			(layers "B.Cu" "B.Mask" "B.Paste")
			(net "_NFP_CORE_VID5")
		)
		(zone
			(layer "B.Cu")
			(hatch none 0.5)
			(connect_pads
				(clearance 0)
			)
			(min_thickness 0.25)
			(keepout
				(tracks not_allowed)
				(vias allowed)
				(pads allowed)
				(copperpour not_allowed)
				(footprints allowed)
			)
			(placement
				(enabled no)
				(sheetname "")
			)
			(fill
				(thermal_gap 0.5)
				(thermal_bridge_width 0.5)
				(island_removal_mode 0)
			)
			(polygon
				(pts
					(xy 32.7406 32.6136) (xy 32.7406 32.6644) (xy 32.7914 32.6644) (xy 32.7914 32.6136)
				)
			)
		)
	)
	(footprint ""
		(layer "B.Cu")
		(at 38.989 46.736)
		(property "Reference" "TP9"
			(at 1.651 -3.27533 0)
			(unlocked yes)
			(layer "B.SilkS")
			(effects
				(font
					(size 0.7874 0.5842)
					(thickness 0.127)
				)
				(justify left mirror)
			)
		)
		(property "Value" "*"
			(at 0.4826 -0.14732 0)
			(unlocked yes)
			(layer "B.Fab")
			(hide yes)
			(effects
				(font
					(size 1.27 0.9652)
					(thickness 0.000001)
				)
				(justify left mirror)
			)
		)
		(property "Device Type" "TP_SMALL"
			(at 0.4826 -0.14732 0)
			(unlocked yes)
			(layer "B.Fab")
			(hide yes)
			(effects
				(font
					(size 1.27 0.9652)
					(thickness 0.000001)
				)
				(justify left mirror)
			)
		)
		(duplicate_pad_numbers_are_jumpers no)
		(fp_line
			(start -0.8636 -0.8636)
			(end 0.8636 -0.8636)
			(stroke
				(width 0.1524)
				(type default)
			)
			(layer "B.SilkS")
		)
		(fp_line
			(start -0.8636 0.8636)
			(end -0.8636 -0.8636)
			(stroke
				(width 0.1524)
				(type default)
			)
			(layer "B.SilkS")
		)
		(fp_line
			(start 0.8636 -0.8636)
			(end 0.8636 0.8636)
			(stroke
				(width 0.1524)
				(type default)
			)
			(layer "B.SilkS")
		)
		(fp_line
			(start 0.8636 0.8636)
			(end -0.8636 0.8636)
			(stroke
				(width 0.1524)
				(type default)
			)
			(layer "B.SilkS")
		)
		(fp_poly
			(pts
				(xy 0.635 -0.635) (xy 0.635 0.635) (xy -0.635 0.635) (xy -0.635 -0.635)
			)
			(stroke
				(width 0)
				(type default)
			)
			(fill no)
			(layer "B.CrtYd")
		)
		(pad "1" smd rect
			(at 0 0 180)
			(size 1.27 1.27)
			(layers "B.Cu" "B.Mask" "B.Paste")
			(net "NFP_JTAG_ARM_TMS")
		)
	)
	(footprint ""
		(layer "B.Cu")
		(at 80.250995 2.699004)
		(property "Reference" "V1_A-WE"
			(at 0 0 0)
			(layer "B.SilkS")
			(hide yes)
			(effects
				(font
					(size 1.27 1.27)
				)
				(justify mirror)
			)
		)
		(property "Value" ""
			(at 0 0 0)
			(layer "B.Fab")
			(effects
				(font
					(size 1.27 1.27)
				)
				(justify mirror)
			)
		)
		(duplicate_pad_numbers_are_jumpers no)
		(pad "1" thru_hole circle
			(at 0 0 180)
			(size 0.4572 0.4572)
			(drill 0.20574)
			(layers "*.Cu" "*.Mask")
			(remove_unused_layers no)
			(net "DDR0_32A_WE_L")
			(clearance 0.1143)
			(thermal_gap 0.1143)
		)
	)
	(footprint ""
		(layer "B.Cu")
		(at 60.579 41.91)
		(property "Reference" "C16"
			(at -0.91567 1.27 270)
			(unlocked yes)
			(layer "B.SilkS")
			(effects
				(font
					(size 0.7874 0.5842)
					(thickness 0.127)
				)
				(justify left mirror)
			)
		)
		(property "Value" "22UF"
			(at 0.148158 1.7526 270)
			(unlocked yes)
			(layer "B.Fab")
			(hide yes)
			(effects
				(font
					(size 1.27 0.9652)
					(thickness 0.000001)
				)
				(justify left mirror)
			)
		)
		(property "Device Type" "CAPC0063"
			(at 0.148158 1.7526 270)
			(unlocked yes)
			(layer "B.Fab")
			(hide yes)
			(effects
				(font
					(size 1.27 0.9652)
					(thickness 0.000001)
				)
				(justify left mirror)
			)
		)
		(duplicate_pad_numbers_are_jumpers no)
		(fp_circle
			(center 0 0)
			(end 0.127 0)
			(stroke
				(width 0.2032)
				(type default)
			)
			(fill no)
			(layer "B.SilkS")
		)
		(fp_poly
			(pts
				(xy -0.7874 -1.6637) (xy 0.7874 -1.6637) (xy 0.7874 1.6637) (xy -0.7874 1.6637)
			)
			(stroke
				(width 0)
				(type default)
			)
			(fill no)
			(layer "B.CrtYd")
		)
		(fp_line
			(start -0.4064 -0.7874)
			(end -0.4064 0.8128)
			(stroke
				(width 0.0254)
				(type default)
			)
			(layer "B.Fab")
		)
		(fp_line
			(start -0.4064 0.8128)
			(end 0.4064 0.8128)
			(stroke
				(width 0.0254)
				(type default)
			)
			(layer "B.Fab")
		)
		(fp_line
			(start 0.4064 -0.7874)
			(end -0.4064 -0.7874)
			(stroke
				(width 0.0254)
				(type default)
			)
			(layer "B.Fab")
		)
		(fp_line
			(start 0.4064 0.8128)
			(end 0.4064 -0.7874)
			(stroke
				(width 0.0254)
				(type default)
			)
			(layer "B.Fab")
		)
		(pad "1" smd rect
			(at 0 -0.8001 180)
			(size 0.8636 0.9652)
			(layers "B.Cu" "B.Mask" "B.Paste")
			(net "VDD_CORE")
		)
		(pad "2" smd rect
			(at 0 0.8001 180)
			(size 0.8636 0.9652)
			(layers "B.Cu" "B.Mask" "B.Paste")
			(net "GND")
		)
		(zone
			(layer "B.Cu")
			(hatch none 0.5)
			(connect_pads
				(clearance 0)
			)
			(min_thickness 0.25)
			(keepout
				(tracks not_allowed)
				(vias allowed)
				(pads allowed)
				(copperpour not_allowed)
				(footprints allowed)
			)
			(placement
				(enabled no)
				(sheetname "")
			)
			(fill
				(thermal_gap 0.5)
				(thermal_bridge_width 0.5)
				(island_removal_mode 0)
			)
			(polygon
				(pts
					(xy 60.6425 41.656) (xy 60.5155 41.656) (xy 60.5155 42.164) (xy 60.6425 42.164)
				)
			)
		)
	)
	(footprint ""
		(layer "B.Cu")
		(at 26.035 22.225 180)
		(property "Reference" "R410"
			(at 0.02667 0.889 270)
			(unlocked yes)
			(layer "B.SilkS")
			(effects
				(font
					(size 0.7874 0.5842)
					(thickness 0.127)
				)
				(justify left mirror)
			)
		)
		(property "Value" "240"
			(at 0.148158 1.3462 90)
			(unlocked yes)
			(layer "B.Fab")
			(hide yes)
			(effects
				(font
					(size 1.27 0.9652)
					(thickness 0.000001)
				)
				(justify left mirror)
			)
		)
		(property "Device Type" "REST0009"
			(at 0.148158 1.3462 90)
			(unlocked yes)
			(layer "B.Fab")
			(hide yes)
			(effects
				(font
					(size 1.27 0.9652)
					(thickness 0.000001)
				)
				(justify left mirror)
			)
		)
		(duplicate_pad_numbers_are_jumpers no)
		(fp_poly
			(pts
				(xy -0.635 1.0668) (xy -0.635 -1.0668) (xy 0.635 -1.0668) (xy 0.635 1.0668)
			)
			(stroke
				(width 0)
				(type default)
			)
			(fill no)
			(layer "B.CrtYd")
		)
		(fp_line
			(start 0.254 0.508)
			(end 0.254 -0.508)
			(stroke
				(width 0.0254)
				(type default)
			)
			(layer "B.Fab")
		)
		(fp_line
			(start 0.254 -0.508)
			(end -0.254 -0.508)
			(stroke
				(width 0.0254)
				(type default)
			)
			(layer "B.Fab")
		)
		(fp_line
			(start -0.254 0.508)
			(end 0.254 0.508)
			(stroke
				(width 0.0254)
				(type default)
			)
			(layer "B.Fab")
		)
		(fp_line
			(start -0.254 -0.508)
			(end -0.254 0.508)
			(stroke
				(width 0.0254)
				(type default)
			)
			(layer "B.Fab")
		)
		(pad "1" smd rect
			(at 0 -0.4191)
			(size 0.508 0.5334)
			(layers "B.Cu" "B.Mask" "B.Paste")
			(net "_NFP_CLK_NRESET_L")
		)
		(pad "2" smd rect
			(at 0 0.4191)
			(size 0.508 0.5334)
			(layers "B.Cu" "B.Mask" "B.Paste")
			(net "NFP_CLK_NRESET_L")
		)
		(zone
			(layer "B.Cu")
			(hatch none 0.5)
			(connect_pads
				(clearance 0)
			)
			(min_thickness 0.25)
			(keepout
				(tracks not_allowed)
				(vias allowed)
				(pads allowed)
				(copperpour not_allowed)
				(footprints allowed)
			)
			(placement
				(enabled no)
				(sheetname "")
			)
			(fill
				(thermal_gap 0.5)
				(thermal_bridge_width 0.5)
				(island_removal_mode 0)
			)
			(polygon
				(pts
					(xy 26.0604 22.2504) (xy 26.0604 22.1996) (xy 26.0096 22.1996) (xy 26.0096 22.2504)
				)
			)
		)
	)
	(footprint ""
		(layer "B.Cu")
		(at 54.737 12.292736 -90)
		(property "Reference" "L3"
			(at -1.725066 -0.635 0)
			(unlocked yes)
			(layer "B.SilkS")
			(effects
				(font
					(size 0.7874 0.5842)
					(thickness 0.127)
				)
				(justify left mirror)
			)
		)
		(property "Value" ""
			(at 0 0 90)
			(layer "B.Fab")
			(effects
				(font
					(size 1.27 1.27)
				)
				(justify mirror)
			)
		)
		(duplicate_pad_numbers_are_jumpers no)
		(fp_rect
			(start -1.7907 0.889)
			(end 1.7907 -0.889)
			(stroke
				(width 0)
				(type default)
			)
			(fill no)
			(layer "B.CrtYd")
		)
		(fp_line
			(start -1.778 0.762)
			(end 1.778 0.762)
			(stroke
				(width 0.0254)
				(type default)
			)
			(layer "B.Fab")
		)
		(fp_line
			(start 1.778 0.762)
			(end 1.778 -0.762)
			(stroke
				(width 0.0254)
				(type default)
			)
			(layer "B.Fab")
		)
		(fp_line
			(start -1.778 -0.762)
			(end -1.778 0.762)
			(stroke
				(width 0.0254)
				(type default)
			)
			(layer "B.Fab")
		)
		(fp_line
			(start 1.778 -0.762)
			(end -1.778 -0.762)
			(stroke
				(width 0.0254)
				(type default)
			)
			(layer "B.Fab")
		)
		(pad "1" smd rect
			(at 0.7493 0)
			(size 0.7874 0.8128)
			(layers "B.Cu" "B.Mask" "B.Paste")
			(net "VDD_CORE")
		)
		(pad "2" smd rect
			(at -0.7493 0)
			(size 0.7874 0.8128)
			(layers "B.Cu" "B.Mask" "B.Paste")
			(net "VDDA_SERDES")
		)
		(zone
			(layer "B.Cu")
			(hatch none 0.5)
			(connect_pads
				(clearance 0)
			)
			(min_thickness 0.25)
			(keepout
				(tracks not_allowed)
				(vias allowed)
				(pads allowed)
				(copperpour not_allowed)
				(footprints allowed)
			)
			(placement
				(enabled no)
				(sheetname "")
			)
			(fill
				(thermal_gap 0.5)
				(thermal_bridge_width 0.5)
				(island_removal_mode 0)
			)
			(polygon
				(pts
					(xy 55.1434 12.572136) (xy 54.3306 12.572136) (xy 54.3306 12.013336) (xy 55.1434 12.013336)
				)
			)
		)
	)
	(footprint ""
		(layer "B.Cu")
		(at 20.701 27.305)
		(property "Reference" "R28"
			(at -0.66167 1.778 270)
			(unlocked yes)
			(layer "B.SilkS")
			(effects
				(font
					(size 0.7874 0.5842)
					(thickness 0.127)
				)
				(justify left mirror)
			)
		)
		(property "Value" "4.75K"
			(at 0.148158 1.3462 270)
			(unlocked yes)
			(layer "B.Fab")
			(hide yes)
			(effects
				(font
					(size 1.27 0.9652)
					(thickness 0.000001)
				)
				(justify left mirror)
			)
		)
		(property "Device Type" "REST4024"
			(at 0.148158 1.3462 270)
			(unlocked yes)
			(layer "B.Fab")
			(hide yes)
			(effects
				(font
					(size 1.27 0.9652)
					(thickness 0.000001)
				)
				(justify left mirror)
			)
		)
		(duplicate_pad_numbers_are_jumpers no)
		(fp_poly
			(pts
				(xy -0.635 1.0668) (xy -0.635 -1.0668) (xy 0.635 -1.0668) (xy 0.635 1.0668)
			)
			(stroke
				(width 0)
				(type default)
			)
			(fill no)
			(layer "B.CrtYd")
		)
		(fp_line
			(start -0.254 -0.508)
			(end -0.254 0.508)
			(stroke
				(width 0.0254)
				(type default)
			)
			(layer "B.Fab")
		)
		(fp_line
			(start -0.254 0.508)
			(end 0.254 0.508)
			(stroke
				(width 0.0254)
				(type default)
			)
			(layer "B.Fab")
		)
		(fp_line
			(start 0.254 -0.508)
			(end -0.254 -0.508)
			(stroke
				(width 0.0254)
				(type default)
			)
			(layer "B.Fab")
		)
		(fp_line
			(start 0.254 0.508)
			(end 0.254 -0.508)
			(stroke
				(width 0.0254)
				(type default)
			)
			(layer "B.Fab")
		)
		(pad "1" smd rect
			(at 0 -0.4191 180)
			(size 0.508 0.5334)
			(layers "B.Cu" "B.Mask" "B.Paste")
			(net "VDD_3.3V")
		)
		(pad "2" smd rect
			(at 0 0.4191 180)
			(size 0.508 0.5334)
			(layers "B.Cu" "B.Mask" "B.Paste")
			(net "NFP_ARM_SPI_FLASH_SEL")
		)
		(zone
			(layer "B.Cu")
			(hatch none 0.5)
			(connect_pads
				(clearance 0)
			)
			(min_thickness 0.25)
			(keepout
				(tracks not_allowed)
				(vias allowed)
				(pads allowed)
				(copperpour not_allowed)
				(footprints allowed)
			)
			(placement
				(enabled no)
				(sheetname "")
			)
			(fill
				(thermal_gap 0.5)
				(thermal_bridge_width 0.5)
				(island_removal_mode 0)
			)
			(polygon
				(pts
					(xy 20.6756 27.2796) (xy 20.6756 27.3304) (xy 20.7264 27.3304) (xy 20.7264 27.2796)
				)
			)
		)
	)
	(footprint ""
		(layer "B.Cu")
		(at 43.5229 41.0845)
		(property "Reference" "R117"
			(at 0 0 0)
			(layer "B.SilkS")
			(hide yes)
			(effects
				(font
					(size 1.27 1.27)
				)
				(justify mirror)
			)
		)
		(property "Value" "2.2"
			(at 0.148158 1.7526 270)
			(unlocked yes)
			(layer "B.Fab")
			(hide yes)
			(effects
				(font
					(size 1.27 0.9652)
					(thickness 0.000001)
				)
				(justify left mirror)
			)
		)
		(property "Device Type" "REST0145"
			(at 0.148158 1.7526 270)
			(unlocked yes)
			(layer "B.Fab")
			(hide yes)
			(effects
				(font
					(size 1.27 0.9652)
					(thickness 0.000001)
				)
				(justify left mirror)
			)
		)
		(duplicate_pad_numbers_are_jumpers no)
		(fp_circle
			(center 0 0)
			(end 0.127 0)
			(stroke
				(width 0.2032)
				(type default)
			)
			(fill no)
			(layer "B.SilkS")
		)
		(fp_poly
			(pts
				(xy -0.7874 -1.6637) (xy 0.7874 -1.6637) (xy 0.7874 1.6637) (xy -0.7874 1.6637)
			)
			(stroke
				(width 0)
				(type default)
			)
			(fill no)
			(layer "B.CrtYd")
		)
		(fp_line
			(start -0.4064 -0.8128)
			(end -0.4064 0.8128)
			(stroke
				(width 0.0254)
				(type default)
			)
			(layer "B.Fab")
		)
		(fp_line
			(start -0.4064 0.8128)
			(end 0.4064 0.8128)
			(stroke
				(width 0.0254)
				(type default)
			)
			(layer "B.Fab")
		)
		(fp_line
			(start 0.4064 -0.8128)
			(end -0.4064 -0.8128)
			(stroke
				(width 0.0254)
				(type default)
			)
			(layer "B.Fab")
		)
		(fp_line
			(start 0.4064 0.8128)
			(end 0.4064 -0.8128)
			(stroke
				(width 0.0254)
				(type default)
			)
			(layer "B.Fab")
		)
		(pad "1" smd rect
			(at 0 -0.8001 180)
			(size 0.762 0.9652)
			(layers "B.Cu" "B.Mask" "B.Paste")
			(net "10N2223")
		)
		(pad "2" smd rect
			(at 0 0.8001 180)
			(size 0.762 0.9652)
			(layers "B.Cu" "B.Mask" "B.Paste")
			(net "L_2_CORE_PHASE")
		)
		(zone
			(layer "B.Cu")
			(hatch none 0.5)
			(connect_pads
				(clearance 0)
			)
			(min_thickness 0.25)
			(keepout
				(tracks not_allowed)
				(vias allowed)
				(pads allowed)
				(copperpour not_allowed)
				(footprints allowed)
			)
			(placement
				(enabled no)
				(sheetname "")
			)
			(fill
				(thermal_gap 0.5)
				(thermal_bridge_width 0.5)
				(island_removal_mode 0)
			)
			(polygon
				(pts
					(xy 43.5864 40.8305) (xy 43.4594 40.8305) (xy 43.4594 41.3385) (xy 43.5864 41.3385)
				)
			)
		)
	)
	(footprint ""
		(layer "B.Cu")
		(at 76.073 43.688)
		(property "Reference" "C140"
			(at 0.48133 4.445 270)
			(unlocked yes)
			(layer "B.SilkS")
			(effects
				(font
					(size 0.7874 0.5842)
					(thickness 0.127)
				)
				(justify left mirror)
			)
		)
		(property "Value" "10UF"
			(at 0.148158 1.7526 270)
			(unlocked yes)
			(layer "B.Fab")
			(hide yes)
			(effects
				(font
					(size 1.27 0.9652)
					(thickness 0.000001)
				)
				(justify left mirror)
			)
		)
		(property "Device Type" "CAPC0058"
			(at 0.148158 1.7526 270)
			(unlocked yes)
			(layer "B.Fab")
			(hide yes)
			(effects
				(font
					(size 1.27 0.9652)
					(thickness 0.000001)
				)
				(justify left mirror)
			)
		)
		(duplicate_pad_numbers_are_jumpers no)
		(fp_circle
			(center 0 0)
			(end 0.127 0)
			(stroke
				(width 0.2032)
				(type default)
			)
			(fill no)
			(layer "B.SilkS")
		)
		(fp_poly
			(pts
				(xy -0.7874 -1.6637) (xy 0.7874 -1.6637) (xy 0.7874 1.6637) (xy -0.7874 1.6637)
			)
			(stroke
				(width 0)
				(type default)
			)
			(fill no)
			(layer "B.CrtYd")
		)
		(fp_line
			(start -0.4064 -0.7874)
			(end -0.4064 0.8128)
			(stroke
				(width 0.0254)
				(type default)
			)
			(layer "B.Fab")
		)
		(fp_line
			(start -0.4064 0.8128)
			(end 0.4064 0.8128)
			(stroke
				(width 0.0254)
				(type default)
			)
			(layer "B.Fab")
		)
		(fp_line
			(start 0.4064 -0.7874)
			(end -0.4064 -0.7874)
			(stroke
				(width 0.0254)
				(type default)
			)
			(layer "B.Fab")
		)
		(fp_line
			(start 0.4064 0.8128)
			(end 0.4064 -0.7874)
			(stroke
				(width 0.0254)
				(type default)
			)
			(layer "B.Fab")
		)
		(pad "1" smd rect
			(at 0 -0.8001 180)
			(size 0.8636 0.9652)
			(layers "B.Cu" "B.Mask" "B.Paste")
			(net "DDR_VTT")
		)
		(pad "2" smd rect
			(at 0 0.8001 180)
			(size 0.8636 0.9652)
			(layers "B.Cu" "B.Mask" "B.Paste")
			(net "GND")
		)
	)
)
